(kicad_pcb
	(version 20260206)
	(generator "pcbnew")
	(generator_version "10.0")
	(general
		(thickness 1.6)
		(legacy_teardrops no)
	)
	(paper "A4")
	(title_block
		(title "03242023_DA0F0TMBIJ0_F0T_Motherboard_J_brd_V01_OCP.brd")
		(comment 1 "Grand Teton / footprints 4891-4897 of 6105")
	)
	(layers
		(0 "F.Cu" signal "TOP")
		(4 "In1.Cu" signal "GND")
		(6 "In2.Cu" signal "IN1")
		(8 "In3.Cu" signal "GND1")
		(10 "In4.Cu" signal "IN2")
		(12 "In5.Cu" signal "GND2")
		(14 "In6.Cu" signal "IN3")
		(16 "In7.Cu" signal "GND3")
		(18 "In8.Cu" signal "VCC")
		(20 "In9.Cu" signal "VCC1")
		(22 "In10.Cu" signal "GND4")
		(24 "In11.Cu" signal "IN4")
		(26 "In12.Cu" signal "GND5")
		(28 "In13.Cu" signal "IN5")
		(30 "In14.Cu" signal "GND6")
		(32 "In15.Cu" signal "IN6")
		(34 "In16.Cu" signal "GND7")
		(2 "B.Cu" signal "BOTTOM")
		(9 "F.Adhes" user "F.Adhesive")
		(11 "B.Adhes" user "B.Adhesive")
		(13 "F.Paste" user "Package Geometry/Pastemask Top")
		(15 "B.Paste" user "Package Geometry/Pastemask Bottom")
		(5 "F.SilkS" user "Ref Des/Silkscreen Top")
		(7 "B.SilkS" user "Ref Des/Silkscreen Bottom")
		(1 "F.Mask" user "Board Geometry/Soldermask Top")
		(3 "B.Mask" user "Board Geometry/Soldermask Bottom")
		(17 "Dwgs.User" user "User.Drawings")
		(19 "Cmts.User" user "User.Comments")
		(21 "Eco1.User" user "User.Eco1")
		(23 "Eco2.User" user "User.Eco2")
		(25 "Edge.Cuts" user "Board Geometry/Outline")
		(27 "Margin" user)
		(31 "F.CrtYd" user "Package Geometry/Place Bound Top")
		(29 "B.CrtYd" user "Package Geometry/Place Bound Bottom")
		(35 "F.Fab" user "Ref Des/Assembly Top")
		(33 "B.Fab" user "Ref Des/Assembly Bottom")
	)
	(footprint ""
		(layer "B.Cu")
		(at 352.097848 -54.435756 90)
		(property "Reference" "C1259"
			(at 0 0 90)
			(layer "B.SilkS")
			(hide yes)
			(effects
				(font
					(size 1.27 1.27)
				)
				(justify mirror)
			)
		)
		(property "Value" ""
			(at 0 0 90)
			(layer "B.Fab")
			(effects
				(font
					(size 1.27 1.27)
				)
				(justify mirror)
			)
		)
		(duplicate_pad_numbers_are_jumpers no)
		(fp_line
			(start 1.524 -0.762)
			(end -1.524 -0.762)
			(stroke
				(width 0.1524)
				(type default)
			)
			(layer "B.SilkS")
		)
		(fp_line
			(start -1.524 -0.762)
			(end -1.524 0.762)
			(stroke
				(width 0.1524)
				(type default)
			)
			(layer "B.SilkS")
		)
		(fp_line
			(start 1.524 0.762)
			(end 1.524 -0.762)
			(stroke
				(width 0.1524)
				(type default)
			)
			(layer "B.SilkS")
		)
		(fp_line
			(start -1.524 0.762)
			(end 1.524 0.762)
			(stroke
				(width 0.1524)
				(type default)
			)
			(layer "B.SilkS")
		)
		(fp_line
			(start 1.1049 -0.724916)
			(end 1.1049 0.724916)
			(stroke
				(width 0.1)
				(type default)
			)
			(layer "B.Fab")
		)
		(fp_line
			(start -1.1049 -0.724916)
			(end 1.1049 -0.724916)
			(stroke
				(width 0.1)
				(type default)
			)
			(layer "B.Fab")
		)
		(fp_line
			(start 1.1049 0.724916)
			(end -1.1049 0.724916)
			(stroke
				(width 0.1)
				(type default)
			)
			(layer "B.Fab")
		)
		(fp_line
			(start -1.1049 0.724916)
			(end -1.1049 -0.724916)
			(stroke
				(width 0.1)
				(type default)
			)
			(layer "B.Fab")
		)
		(pad "1" smd rect
			(at 0.889 0 90)
			(size 1.016 1.27)
			(layers "B.Cu" "B.Mask" "B.Paste")
			(net "P1V8_PCH_PLL_AUX")
		)
		(pad "2" smd rect
			(at -0.889 0 90)
			(size 1.016 1.27)
			(layers "B.Cu" "B.Mask" "B.Paste")
			(net "GND")
		)
	)
	(footprint ""
		(layer "B.Cu")
		(at 259.37464 -49.430686 180)
		(property "Reference" "PC2341"
			(at 0 0 0)
			(layer "B.SilkS")
			(hide yes)
			(effects
				(font
					(size 1.27 1.27)
				)
				(justify mirror)
			)
		)
		(property "Value" ""
			(at 0 0 0)
			(layer "B.Fab")
			(effects
				(font
					(size 1.27 1.27)
				)
				(justify mirror)
			)
		)
		(duplicate_pad_numbers_are_jumpers no)
		(fp_line
			(start 0.7874 0.4064)
			(end 0.7874 -0.4064)
			(stroke
				(width 0.1524)
				(type default)
			)
			(layer "B.SilkS")
		)
		(fp_line
			(start 0.7874 -0.4064)
			(end -0.7874 -0.4064)
			(stroke
				(width 0.1524)
				(type default)
			)
			(layer "B.SilkS")
		)
		(fp_line
			(start -0.7874 0.4064)
			(end 0.7874 0.4064)
			(stroke
				(width 0.1524)
				(type default)
			)
			(layer "B.SilkS")
		)
		(fp_line
			(start -0.7874 -0.4064)
			(end -0.7874 0.4064)
			(stroke
				(width 0.1524)
				(type default)
			)
			(layer "B.SilkS")
		)
		(fp_line
			(start 0.67945 0.3048)
			(end 0.67945 -0.305054)
			(stroke
				(width 0.1)
				(type default)
			)
			(layer "B.Fab")
		)
		(fp_line
			(start 0.67945 -0.305054)
			(end 0.12065 -0.305054)
			(stroke
				(width 0.1)
				(type default)
			)
			(layer "B.Fab")
		)
		(fp_line
			(start 0.12065 0.3048)
			(end 0.67945 0.3048)
			(stroke
				(width 0.1)
				(type default)
			)
			(layer "B.Fab")
		)
		(fp_line
			(start 0.12065 0.2794)
			(end 0.12065 0.3048)
			(stroke
				(width 0.1)
				(type default)
			)
			(layer "B.Fab")
		)
		(fp_line
			(start 0.12065 -0.2794)
			(end -0.12065 -0.2794)
			(stroke
				(width 0.1)
				(type default)
			)
			(layer "B.Fab")
		)
		(fp_line
			(start 0.12065 -0.305054)
			(end 0.12065 -0.2794)
			(stroke
				(width 0.1)
				(type default)
			)
			(layer "B.Fab")
		)
		(fp_line
			(start -0.120396 0.3048)
			(end -0.120396 0.2794)
			(stroke
				(width 0.1)
				(type default)
			)
			(layer "B.Fab")
		)
		(fp_line
			(start -0.120396 0.2794)
			(end 0.12065 0.2794)
			(stroke
				(width 0.1)
				(type default)
			)
			(layer "B.Fab")
		)
		(fp_line
			(start -0.12065 -0.2794)
			(end -0.12065 -0.3048)
			(stroke
				(width 0.1)
				(type default)
			)
			(layer "B.Fab")
		)
		(fp_line
			(start -0.12065 -0.3048)
			(end -0.67945 -0.3048)
			(stroke
				(width 0.1)
				(type default)
			)
			(layer "B.Fab")
		)
		(fp_line
			(start -0.67945 0.3048)
			(end -0.120396 0.3048)
			(stroke
				(width 0.1)
				(type default)
			)
			(layer "B.Fab")
		)
		(fp_line
			(start -0.67945 -0.3048)
			(end -0.67945 0.3048)
			(stroke
				(width 0.1)
				(type default)
			)
			(layer "B.Fab")
		)
		(pad "1" smd circle
			(at 0.40005 0)
			(size 0 0)
			(layers "B.Cu" "B.Mask" "B.Paste")
			(net "P12V_E1S_ISET_0_R")
		)
		(pad "2" smd circle
			(at -0.40005 0)
			(size 0 0)
			(layers "B.Cu" "B.Mask" "B.Paste")
			(net "GND")
		)
	)
	(footprint ""
		(layer "B.Cu")
		(at 372.613936 -325.098156 -90)
		(property "Reference" "PC310_P0_1"
			(at 0 0 90)
			(layer "B.SilkS")
			(hide yes)
			(effects
				(font
					(size 1.27 1.27)
				)
				(justify mirror)
			)
		)
		(property "Value" ""
			(at 0 0 90)
			(layer "B.Fab")
			(effects
				(font
					(size 1.27 1.27)
				)
				(justify mirror)
			)
		)
		(duplicate_pad_numbers_are_jumpers no)
		(fp_line
			(start -0.7874 0.4064)
			(end 0.7874 0.4064)
			(stroke
				(width 0.1524)
				(type default)
			)
			(layer "B.SilkS")
		)
		(fp_line
			(start 0.7874 0.4064)
			(end 0.7874 -0.4064)
			(stroke
				(width 0.1524)
				(type default)
			)
			(layer "B.SilkS")
		)
		(fp_line
			(start -0.7874 -0.4064)
			(end -0.7874 0.4064)
			(stroke
				(width 0.1524)
				(type default)
			)
			(layer "B.SilkS")
		)
		(fp_line
			(start 0.7874 -0.4064)
			(end -0.7874 -0.4064)
			(stroke
				(width 0.1524)
				(type default)
			)
			(layer "B.SilkS")
		)
		(fp_line
			(start -0.67945 0.3048)
			(end -0.120396 0.3048)
			(stroke
				(width 0.1)
				(type default)
			)
			(layer "B.Fab")
		)
		(fp_line
			(start -0.120396 0.3048)
			(end -0.120396 0.2794)
			(stroke
				(width 0.1)
				(type default)
			)
			(layer "B.Fab")
		)
		(fp_line
			(start 0.12065 0.3048)
			(end 0.67945 0.3048)
			(stroke
				(width 0.1)
				(type default)
			)
			(layer "B.Fab")
		)
		(fp_line
			(start 0.67945 0.3048)
			(end 0.67945 -0.305054)
			(stroke
				(width 0.1)
				(type default)
			)
			(layer "B.Fab")
		)
		(fp_line
			(start -0.120396 0.2794)
			(end 0.12065 0.2794)
			(stroke
				(width 0.1)
				(type default)
			)
			(layer "B.Fab")
		)
		(fp_line
			(start 0.12065 0.2794)
			(end 0.12065 0.3048)
			(stroke
				(width 0.1)
				(type default)
			)
			(layer "B.Fab")
		)
		(fp_line
			(start -0.12065 -0.2794)
			(end -0.12065 -0.3048)
			(stroke
				(width 0.1)
				(type default)
			)
			(layer "B.Fab")
		)
		(fp_line
			(start 0.12065 -0.2794)
			(end -0.12065 -0.2794)
			(stroke
				(width 0.1)
				(type default)
			)
			(layer "B.Fab")
		)
		(fp_line
			(start -0.67945 -0.3048)
			(end -0.67945 0.3048)
			(stroke
				(width 0.1)
				(type default)
			)
			(layer "B.Fab")
		)
		(fp_line
			(start -0.12065 -0.3048)
			(end -0.67945 -0.3048)
			(stroke
				(width 0.1)
				(type default)
			)
			(layer "B.Fab")
		)
		(fp_line
			(start 0.12065 -0.305054)
			(end 0.12065 -0.2794)
			(stroke
				(width 0.1)
				(type default)
			)
			(layer "B.Fab")
		)
		(fp_line
			(start 0.67945 -0.305054)
			(end 0.12065 -0.305054)
			(stroke
				(width 0.1)
				(type default)
			)
			(layer "B.Fab")
		)
		(pad "1" smd circle
			(at 0.40005 0 90)
			(size 0 0)
			(layers "B.Cu" "B.Mask" "B.Paste")
			(net "PVCCIN_CPU0")
		)
		(pad "2" smd circle
			(at -0.40005 0 90)
			(size 0 0)
			(layers "B.Cu" "B.Mask" "B.Paste")
			(net "GND")
		)
	)
	(footprint ""
		(layer "B.Cu")
		(at 116.40312 -241.14252 -90)
		(property "Reference" "C311"
			(at 0 0 90)
			(layer "B.SilkS")
			(hide yes)
			(effects
				(font
					(size 1.27 1.27)
				)
				(justify mirror)
			)
		)
		(property "Value" ""
			(at 0 0 90)
			(layer "B.Fab")
			(effects
				(font
					(size 1.27 1.27)
				)
				(justify mirror)
			)
		)
		(duplicate_pad_numbers_are_jumpers no)
		(fp_line
			(start -1.524 0.762)
			(end 1.524 0.762)
			(stroke
				(width 0.1524)
				(type default)
			)
			(layer "B.SilkS")
		)
		(fp_line
			(start 1.524 0.762)
			(end 1.524 -0.762)
			(stroke
				(width 0.1524)
				(type default)
			)
			(layer "B.SilkS")
		)
		(fp_line
			(start -1.524 -0.762)
			(end -1.524 0.762)
			(stroke
				(width 0.1524)
				(type default)
			)
			(layer "B.SilkS")
		)
		(fp_line
			(start 1.524 -0.762)
			(end -1.524 -0.762)
			(stroke
				(width 0.1524)
				(type default)
			)
			(layer "B.SilkS")
		)
		(fp_line
			(start -1.1049 0.724916)
			(end -1.1049 -0.724916)
			(stroke
				(width 0.1)
				(type default)
			)
			(layer "B.Fab")
		)
		(fp_line
			(start 1.1049 0.724916)
			(end -1.1049 0.724916)
			(stroke
				(width 0.1)
				(type default)
			)
			(layer "B.Fab")
		)
		(fp_line
			(start -1.1049 -0.724916)
			(end 1.1049 -0.724916)
			(stroke
				(width 0.1)
				(type default)
			)
			(layer "B.Fab")
		)
		(fp_line
			(start 1.1049 -0.724916)
			(end 1.1049 0.724916)
			(stroke
				(width 0.1)
				(type default)
			)
			(layer "B.Fab")
		)
		(pad "1" smd rect
			(at 0.889 0 270)
			(size 1.016 1.27)
			(layers "B.Cu" "B.Mask" "B.Paste")
			(net "PVCCIN_CPU1")
		)
		(pad "2" smd rect
			(at -0.889 0 270)
			(size 1.016 1.27)
			(layers "B.Cu" "B.Mask" "B.Paste")
			(net "GND")
		)
	)
	(footprint ""
		(layer "B.Cu")
		(at 339.97773 -190.703454 90)
		(property "Reference" "R1237"
			(at 0 0 90)
			(layer "B.SilkS")
			(hide yes)
			(effects
				(font
					(size 1.27 1.27)
				)
				(justify mirror)
			)
		)
		(property "Value" ""
			(at 0 0 90)
			(layer "B.Fab")
			(effects
				(font
					(size 1.27 1.27)
				)
				(justify mirror)
			)
		)
		(duplicate_pad_numbers_are_jumpers no)
		(fp_line
			(start 0.7874 -0.4064)
			(end -0.7874 -0.4064)
			(stroke
				(width 0.1524)
				(type default)
			)
			(layer "B.SilkS")
		)
		(fp_line
			(start -0.7874 -0.4064)
			(end -0.7874 0.4064)
			(stroke
				(width 0.1524)
				(type default)
			)
			(layer "B.SilkS")
		)
		(fp_line
			(start 0.7874 0.4064)
			(end 0.7874 -0.4064)
			(stroke
				(width 0.1524)
				(type default)
			)
			(layer "B.SilkS")
		)
		(fp_line
			(start -0.7874 0.4064)
			(end 0.7874 0.4064)
			(stroke
				(width 0.1524)
				(type default)
			)
			(layer "B.SilkS")
		)
		(fp_line
			(start 0.67945 -0.305054)
			(end 0.12065 -0.305054)
			(stroke
				(width 0.1)
				(type default)
			)
			(layer "B.Fab")
		)
		(fp_line
			(start 0.12065 -0.305054)
			(end 0.12065 -0.2794)
			(stroke
				(width 0.1)
				(type default)
			)
			(layer "B.Fab")
		)
		(fp_line
			(start -0.12065 -0.3048)
			(end -0.67945 -0.3048)
			(stroke
				(width 0.1)
				(type default)
			)
			(layer "B.Fab")
		)
		(fp_line
			(start -0.67945 -0.3048)
			(end -0.67945 0.3048)
			(stroke
				(width 0.1)
				(type default)
			)
			(layer "B.Fab")
		)
		(fp_line
			(start 0.12065 -0.2794)
			(end -0.12065 -0.2794)
			(stroke
				(width 0.1)
				(type default)
			)
			(layer "B.Fab")
		)
		(fp_line
			(start -0.12065 -0.2794)
			(end -0.12065 -0.3048)
			(stroke
				(width 0.1)
				(type default)
			)
			(layer "B.Fab")
		)
		(fp_line
			(start 0.12065 0.2794)
			(end 0.12065 0.3048)
			(stroke
				(width 0.1)
				(type default)
			)
			(layer "B.Fab")
		)
		(fp_line
			(start -0.120396 0.2794)
			(end 0.12065 0.2794)
			(stroke
				(width 0.1)
				(type default)
			)
			(layer "B.Fab")
		)
		(fp_line
			(start 0.67945 0.3048)
			(end 0.67945 -0.305054)
			(stroke
				(width 0.1)
				(type default)
			)
			(layer "B.Fab")
		)
		(fp_line
			(start 0.12065 0.3048)
			(end 0.67945 0.3048)
			(stroke
				(width 0.1)
				(type default)
			)
			(layer "B.Fab")
		)
		(fp_line
			(start -0.120396 0.3048)
			(end -0.120396 0.2794)
			(stroke
				(width 0.1)
				(type default)
			)
			(layer "B.Fab")
		)
		(fp_line
			(start -0.67945 0.3048)
			(end -0.120396 0.3048)
			(stroke
				(width 0.1)
				(type default)
			)
			(layer "B.Fab")
		)
		(pad "1" smd circle
			(at 0.40005 0 270)
			(size 0 0)
			(layers "B.Cu" "B.Mask" "B.Paste")
			(net "GND")
		)
		(pad "2" smd circle
			(at -0.40005 0 270)
			(size 0 0)
			(layers "B.Cu" "B.Mask" "B.Paste")
			(net "PD_EXT_CLK_SEL_CPU0")
		)
	)
	(footprint ""
		(layer "B.Cu")
		(at 362.629704 -358.675432 180)
		(property "Reference" "PR400"
			(at 0 0 0)
			(layer "B.SilkS")
			(hide yes)
			(effects
				(font
					(size 1.27 1.27)
				)
				(justify mirror)
			)
		)
		(property "Value" ""
			(at 0 0 0)
			(layer "B.Fab")
			(effects
				(font
					(size 1.27 1.27)
				)
				(justify mirror)
			)
		)
		(duplicate_pad_numbers_are_jumpers no)
		(fp_line
			(start 0.7874 0.4064)
			(end 0.7874 -0.4064)
			(stroke
				(width 0.1524)
				(type default)
			)
			(layer "B.SilkS")
		)
		(fp_line
			(start 0.7874 -0.4064)
			(end -0.7874 -0.4064)
			(stroke
				(width 0.1524)
				(type default)
			)
			(layer "B.SilkS")
		)
		(fp_line
			(start -0.7874 0.4064)
			(end 0.7874 0.4064)
			(stroke
				(width 0.1524)
				(type default)
			)
			(layer "B.SilkS")
		)
		(fp_line
			(start -0.7874 -0.4064)
			(end -0.7874 0.4064)
			(stroke
				(width 0.1524)
				(type default)
			)
			(layer "B.SilkS")
		)
		(fp_line
			(start 0.67945 0.3048)
			(end 0.67945 -0.305054)
			(stroke
				(width 0.1)
				(type default)
			)
			(layer "B.Fab")
		)
		(fp_line
			(start 0.67945 -0.305054)
			(end 0.12065 -0.305054)
			(stroke
				(width 0.1)
				(type default)
			)
			(layer "B.Fab")
		)
		(fp_line
			(start 0.12065 0.3048)
			(end 0.67945 0.3048)
			(stroke
				(width 0.1)
				(type default)
			)
			(layer "B.Fab")
		)
		(fp_line
			(start 0.12065 0.2794)
			(end 0.12065 0.3048)
			(stroke
				(width 0.1)
				(type default)
			)
			(layer "B.Fab")
		)
		(fp_line
			(start 0.12065 -0.2794)
			(end -0.12065 -0.2794)
			(stroke
				(width 0.1)
				(type default)
			)
			(layer "B.Fab")
		)
		(fp_line
			(start 0.12065 -0.305054)
			(end 0.12065 -0.2794)
			(stroke
				(width 0.1)
				(type default)
			)
			(layer "B.Fab")
		)
		(fp_line
			(start -0.120396 0.3048)
			(end -0.120396 0.2794)
			(stroke
				(width 0.1)
				(type default)
			)
			(layer "B.Fab")
		)
		(fp_line
			(start -0.120396 0.2794)
			(end 0.12065 0.2794)
			(stroke
				(width 0.1)
				(type default)
			)
			(layer "B.Fab")
		)
		(fp_line
			(start -0.12065 -0.2794)
			(end -0.12065 -0.3048)
			(stroke
				(width 0.1)
				(type default)
			)
			(layer "B.Fab")
		)
		(fp_line
			(start -0.12065 -0.3048)
			(end -0.67945 -0.3048)
			(stroke
				(width 0.1)
				(type default)
			)
			(layer "B.Fab")
		)
		(fp_line
			(start -0.67945 0.3048)
			(end -0.120396 0.3048)
			(stroke
				(width 0.1)
				(type default)
			)
			(layer "B.Fab")
		)
		(fp_line
			(start -0.67945 -0.3048)
			(end -0.67945 0.3048)
			(stroke
				(width 0.1)
				(type default)
			)
			(layer "B.Fab")
		)
		(pad "1" smd circle
			(at 0.40005 0)
			(size 0 0)
			(layers "B.Cu" "B.Mask" "B.Paste")
			(net "PVCCIN_CPU0_ATSEN")
		)
		(pad "2" smd circle
			(at -0.40005 0)
			(size 0 0)
			(layers "B.Cu" "B.Mask" "B.Paste")
			(net "GND")
		)
	)
	(footprint ""
		(layer "B.Cu")
		(at 115.195604 -294.01008 180)
		(property "Reference" "C343"
			(at 0 0 0)
			(layer "B.SilkS")
			(hide yes)
			(effects
				(font
					(size 1.27 1.27)
				)
				(justify mirror)
			)
		)
		(property "Value" ""
			(at 0 0 0)
			(layer "B.Fab")
			(effects
				(font
					(size 1.27 1.27)
				)
				(justify mirror)
			)
		)
		(duplicate_pad_numbers_are_jumpers no)
		(fp_line
			(start 1.524 0.762)
			(end 1.524 -0.762)
			(stroke
				(width 0.1524)
				(type default)
			)
			(layer "B.SilkS")
		)
		(fp_line
			(start 1.524 -0.762)
			(end -1.524 -0.762)
			(stroke
				(width 0.1524)
				(type default)
			)
			(layer "B.SilkS")
		)
		(fp_line
			(start -1.524 0.762)
			(end 1.524 0.762)
			(stroke
				(width 0.1524)
				(type default)
			)
			(layer "B.SilkS")
		)
		(fp_line
			(start -1.524 -0.762)
			(end -1.524 0.762)
			(stroke
				(width 0.1524)
				(type default)
			)
			(layer "B.SilkS")
		)
		(fp_line
			(start 1.1049 0.724916)
			(end -1.1049 0.724916)
			(stroke
				(width 0.1)
				(type default)
			)
			(layer "B.Fab")
		)
		(fp_line
			(start 1.1049 -0.724916)
			(end 1.1049 0.724916)
			(stroke
				(width 0.1)
				(type default)
			)
			(layer "B.Fab")
		)
		(fp_line
			(start -1.1049 0.724916)
			(end -1.1049 -0.724916)
			(stroke
				(width 0.1)
				(type default)
			)
			(layer "B.Fab")
		)
		(fp_line
			(start -1.1049 -0.724916)
			(end 1.1049 -0.724916)
			(stroke
				(width 0.1)
				(type default)
			)
			(layer "B.Fab")
		)
		(pad "1" smd rect
			(at 0.889 0 180)
			(size 1.016 1.27)
			(layers "B.Cu" "B.Mask" "B.Paste")
			(net "PVCCIN_CPU1")
		)
		(pad "2" smd rect
			(at -0.889 0 180)
			(size 1.016 1.27)
			(layers "B.Cu" "B.Mask" "B.Paste")
			(net "GND")
		)
	)
)
